# BASEBOARD_FAB2 (Tioga Pass) — schematic netlist excerpt (pin names and nets, part order shuffled) for the footprints in the layout excerpt that follows; sources: Cadence DE-HDL packaged netlist, KiCad conversion of Wiwynn_Tioga_Pass_MB.brd

C3P34  CAP  0.22UF 16V 10% X7R  pkg 0402  page 107 : A = P3E_CPU0_PE1_SS_TXP<6> ; B = P3E_CPU0_PE1_SS_C_TXP<6>
R25W122  RES  20.0 1% CHIP  pkg 0402  page 145 : A = SMB_PEHPCPU0_STBY_LVC3_R_SCL ; B = SMB_PEHPCPU0_STBY_LVC3_R2_SCL
C9L8  CAP_A  0.01UF 25V 10% X7R  pkg 0402V  page 100 : A = M_L_CPU_VREF ; B = GND

(kicad_pcb
	(version 20260206)
	(generator "pcbnew")
	(generator_version "10.0")
	(general
		(thickness 1.6)
		(legacy_teardrops no)
	)
	(paper "A4")
	(title_block
		(title "Wiwynn_Tioga_Pass_MB.brd")
		(comment 1 "Tioga Pass / footprints 4294-4296 of 4770")
	)
	(layers
		(0 "F.Cu" signal "TOP")
		(4 "In1.Cu" signal "L2GND")
		(6 "In2.Cu" signal "L3")
		(8 "In3.Cu" signal "L4GND")
		(10 "In4.Cu" signal "L5")
		(12 "In5.Cu" signal "L6GND")
		(14 "In6.Cu" signal "L7VCC")
		(16 "In7.Cu" signal "L8VCC")
		(18 "In8.Cu" signal "L9GND")
		(20 "In9.Cu" signal "L10")
		(22 "In10.Cu" signal "L11GND")
		(24 "In11.Cu" signal "L12")
		(26 "In12.Cu" signal "L13GND")
		(2 "B.Cu" signal "BOTTOM")
		(9 "F.Adhes" user "F.Adhesive")
		(11 "B.Adhes" user "B.Adhesive")
		(13 "F.Paste" user "Package Geometry/Pastemask Top")
		(15 "B.Paste" user "Package Geometry/Pastemask Bottom")
		(5 "F.SilkS" user "Ref Des/Silkscreen Top")
		(7 "B.SilkS" user "Ref Des/Silkscreen Bottom")
		(1 "F.Mask" user "Board Geometry/Soldermask Top")
		(3 "B.Mask" user "Board Geometry/Soldermask Bottom")
		(17 "Dwgs.User" user "User.Drawings")
		(19 "Cmts.User" user "User.Comments")
		(21 "Eco1.User" user "User.Eco1")
		(23 "Eco2.User" user "User.Eco2")
		(25 "Edge.Cuts" user "Board Geometry/Outline")
		(27 "Margin" user)
		(31 "F.CrtYd" user "Package Geometry/Place Bound Top")
		(29 "B.CrtYd" user "Package Geometry/Place Bound Bottom")
		(35 "F.Fab" user "Ref Des/Assembly Top")
		(33 "B.Fab" user "Ref Des/Assembly Bottom")
	)
	(footprint ""
		(layer "B.Cu")
		(at 26.769568 -144.4752 180)
		(property "Reference" "C9L8"
			(at 0 0 0)
			(layer "B.SilkS")
			(hide yes)
			(effects
				(font
					(size 1.27 1.27)
				)
				(justify mirror)
			)
		)
		(property "Value" ""
			(at 0 0 0)
			(layer "B.Fab")
			(effects
				(font
					(size 1.27 1.27)
				)
				(justify mirror)
			)
		)
		(duplicate_pad_numbers_are_jumpers no)
		(fp_poly
			(pts
				(xy -0.3048 -0.1016) (xy -0.3048 0.9906) (xy 0.3048 0.9906) (xy 0.3048 -0.1016)
			)
			(stroke
				(width 0)
				(type default)
			)
			(fill no)
			(layer "B.CrtYd")
		)
		(fp_line
			(start 0.3048 0.9906)
			(end -0.3048 0.9906)
			(stroke
				(width 0.1)
				(type default)
			)
			(layer "B.Fab")
		)
		(fp_line
			(start 0.3048 -0.1016)
			(end 0.3048 0.9906)
			(stroke
				(width 0.1)
				(type default)
			)
			(layer "B.Fab")
		)
		(fp_line
			(start -0.3048 0.9906)
			(end -0.3048 -0.1016)
			(stroke
				(width 0.1)
				(type default)
			)
			(layer "B.Fab")
		)
		(fp_line
			(start -0.3048 -0.1016)
			(end 0.3048 -0.1016)
			(stroke
				(width 0.1)
				(type default)
			)
			(layer "B.Fab")
		)
		(pad "1" smd rect
			(at 0 0)
			(size 0.508 0.508)
			(layers "B.Cu" "B.Mask" "B.Paste")
			(net "M_L_CPU_VREF")
		)
		(pad "2" smd rect
			(at 0 0.889)
			(size 0.508 0.508)
			(layers "B.Cu" "B.Mask" "B.Paste")
			(net "GND")
		)
		(zone
			(layer "B.Cu")
			(hatch none 0.5)
			(connect_pads
				(clearance 0)
			)
			(min_thickness 0.25)
			(keepout
				(tracks not_allowed)
				(vias allowed)
				(pads allowed)
				(copperpour not_allowed)
				(footprints allowed)
			)
			(placement
				(enabled no)
				(sheetname "")
			)
			(fill
				(thermal_gap 0.5)
				(thermal_bridge_width 0.5)
				(island_removal_mode 0)
			)
			(polygon
				(pts
					(xy 26.515568 -145.1102) (xy 27.023568 -145.1102) (xy 27.023568 -144.7292) (xy 26.515568 -144.7292)
				)
			)
		)
		(zone
			(layer "B.Cu")
			(hatch none 0.5)
			(connect_pads
				(clearance 0)
			)
			(min_thickness 0.25)
			(keepout
				(tracks allowed)
				(vias not_allowed)
				(pads allowed)
				(copperpour not_allowed)
				(footprints allowed)
			)
			(placement
				(enabled no)
				(sheetname "")
			)
			(fill
				(thermal_gap 0.5)
				(thermal_bridge_width 0.5)
				(island_removal_mode 0)
			)
			(polygon
				(pts
					(xy 26.515568 -144.7292) (xy 27.023568 -144.7292) (xy 27.023568 -145.1102) (xy 26.515568 -145.1102)
				)
			)
		)
	)
	(footprint ""
		(layer "B.Cu")
		(at 405.358854 -35.09391 90)
		(property "Reference" "R25W122"
			(at 0.8382 -0.67818 90)
			(unlocked yes)
			(layer "B.SilkS")
			(effects
				(font
					(size 0.4064 0.254)
					(thickness 0.1524)
				)
				(justify left mirror)
			)
		)
		(property "Value" ""
			(at 0 0 90)
			(layer "B.Fab")
			(effects
				(font
					(size 1.27 1.27)
				)
				(justify mirror)
			)
		)
		(duplicate_pad_numbers_are_jumpers no)
		(fp_poly
			(pts
				(xy 0.2794 -0.1016) (xy -0.2794 -0.1016) (xy -0.2794 0.9906) (xy 0.2794 0.9906)
			)
			(stroke
				(width 0)
				(type default)
			)
			(fill no)
			(layer "B.CrtYd")
		)
		(fp_line
			(start 0.2794 -0.1016)
			(end 0.2794 0.9906)
			(stroke
				(width 0.1)
				(type default)
			)
			(layer "B.Fab")
		)
		(fp_line
			(start -0.2794 -0.1016)
			(end 0.2794 -0.1016)
			(stroke
				(width 0.1)
				(type default)
			)
			(layer "B.Fab")
		)
		(fp_line
			(start 0.2794 0.9906)
			(end -0.2794 0.9906)
			(stroke
				(width 0.1)
				(type default)
			)
			(layer "B.Fab")
		)
		(fp_line
			(start -0.2794 0.9906)
			(end -0.2794 -0.1016)
			(stroke
				(width 0.1)
				(type default)
			)
			(layer "B.Fab")
		)
		(pad "1" smd rect
			(at 0 0 270)
			(size 0.508 0.508)
			(layers "B.Cu" "B.Mask" "B.Paste")
			(net "SMB_PEHPCPU0_STBY_LVC3_R_SCL")
		)
		(pad "2" smd rect
			(at 0 0.889 270)
			(size 0.508 0.508)
			(layers "B.Cu" "B.Mask" "B.Paste")
			(net "SMB_PEHPCPU0_STBY_LVC3_R2_SCL")
		)
		(zone
			(layer "B.Cu")
			(hatch none 0.5)
			(connect_pads
				(clearance 0)
			)
			(min_thickness 0.25)
			(keepout
				(tracks allowed)
				(vias not_allowed)
				(pads allowed)
				(copperpour not_allowed)
				(footprints allowed)
			)
			(placement
				(enabled no)
				(sheetname "")
			)
			(fill
				(thermal_gap 0.5)
				(thermal_bridge_width 0.5)
				(island_removal_mode 0)
			)
			(polygon
				(pts
					(xy 405.612854 -35.34791) (xy 405.612854 -34.83991) (xy 405.993854 -34.83991) (xy 405.993854 -35.34791)
				)
			)
		)
		(zone
			(layer "B.Cu")
			(hatch none 0.5)
			(connect_pads
				(clearance 0)
			)
			(min_thickness 0.25)
			(keepout
				(tracks not_allowed)
				(vias allowed)
				(pads allowed)
				(copperpour not_allowed)
				(footprints allowed)
			)
			(placement
				(enabled no)
				(sheetname "")
			)
			(fill
				(thermal_gap 0.5)
				(thermal_bridge_width 0.5)
				(island_removal_mode 0)
			)
			(polygon
				(pts
					(xy 405.993854 -35.34791) (xy 405.993854 -34.83991) (xy 405.612854 -34.83991) (xy 405.612854 -35.34791)
				)
			)
		)
	)
	(footprint ""
		(layer "B.Cu")
		(at 355.736398 -77.915516)
		(property "Reference" "C3P34"
			(at 0 0 0)
			(layer "B.SilkS")
			(hide yes)
			(effects
				(font
					(size 1.27 1.27)
				)
				(justify mirror)
			)
		)
		(property "Value" ""
			(at 0 0 0)
			(layer "B.Fab")
			(effects
				(font
					(size 1.27 1.27)
				)
				(justify mirror)
			)
		)
		(duplicate_pad_numbers_are_jumpers no)
		(fp_poly
			(pts
				(xy -0.3048 -0.1016) (xy -0.3048 0.9906) (xy 0.3048 0.9906) (xy 0.3048 -0.1016)
			)
			(stroke
				(width 0)
				(type default)
			)
			(fill no)
			(layer "B.CrtYd")
		)
		(fp_line
			(start -0.3048 -0.1016)
			(end 0.3048 -0.1016)
			(stroke
				(width 0.1)
				(type default)
			)
			(layer "B.Fab")
		)
		(fp_line
			(start -0.3048 0.9906)
			(end -0.3048 -0.1016)
			(stroke
				(width 0.1)
				(type default)
			)
			(layer "B.Fab")
		)
		(fp_line
			(start 0.3048 -0.1016)
			(end 0.3048 0.9906)
			(stroke
				(width 0.1)
				(type default)
			)
			(layer "B.Fab")
		)
		(fp_line
			(start 0.3048 0.9906)
			(end -0.3048 0.9906)
			(stroke
				(width 0.1)
				(type default)
			)
			(layer "B.Fab")
		)
		(pad "1" smd rect
			(at 0 0 180)
			(size 0.508 0.508)
			(layers "B.Cu" "B.Mask" "B.Paste")
			(net "P3E_CPU0_PE1_SS_TXP<6>")
		)
		(pad "2" smd rect
			(at 0 0.889 180)
			(size 0.508 0.508)
			(layers "B.Cu" "B.Mask" "B.Paste")
			(net "P3E_CPU0_PE1_SS_C_TXP<6>")
		)
		(zone
			(layer "B.Cu")
			(hatch none 0.5)
			(connect_pads
				(clearance 0)
			)
			(min_thickness 0.25)
			(keepout
				(tracks allowed)
				(vias not_allowed)
				(pads allowed)
				(copperpour not_allowed)
				(footprints allowed)
			)
			(placement
				(enabled no)
				(sheetname "")
			)
			(fill
				(thermal_gap 0.5)
				(thermal_bridge_width 0.5)
				(island_removal_mode 0)
			)
			(polygon
				(pts
					(xy 355.990398 -77.661516) (xy 355.482398 -77.661516) (xy 355.482398 -77.280516) (xy 355.990398 -77.280516)
				)
			)
		)
		(zone
			(layer "B.Cu")
			(hatch none 0.5)
			(connect_pads
				(clearance 0)
			)
			(min_thickness 0.25)
			(keepout
				(tracks not_allowed)
				(vias allowed)
				(pads allowed)
				(copperpour not_allowed)
				(footprints allowed)
			)
			(placement
				(enabled no)
				(sheetname "")
			)
			(fill
				(thermal_gap 0.5)
				(thermal_bridge_width 0.5)
				(island_removal_mode 0)
			)
			(polygon
				(pts
					(xy 355.990398 -77.280516) (xy 355.482398 -77.280516) (xy 355.482398 -77.661516) (xy 355.990398 -77.661516)
				)
			)
		)
	)
)
